# TIMECARD (Time Appliance Project (Time Card)) — schematic netlist excerpt (pin names and nets, part order shuffled) for the footprints in the layout excerpt that follows; sources: Cadence DE-HDL packaged netlist, KiCad conversion of R4006-B0001-02_R01.brd

R299  RESISTOR  33OHM 1%  pkg SMC_0402R_H016  page 18 : \1\ = R_SHT3X_ALERT_N ; \2\ = FPGA_IN_SHT3X_ALERT_N
R490  RESISTOR  10KOHM 1%  pkg SMC_0402R_H016  page 33 : \1\ = XP3R3V_FT4232 ; \2\ = UNNAMED_525_ISL80101IRAJZDFN10_

(kicad_pcb
	(version 20260206)
	(generator "pcbnew")
	(generator_version "10.0")
	(general
		(thickness 1.6)
		(legacy_teardrops no)
	)
	(paper "A4")
	(title_block
		(title "timecard-production-celestica-r4006 — R4006-B0001-02_R01.brd")
		(comment 1 "Time Appliance Project (Time Card) / footprints 415-416 of 1113")
	)
	(layers
		(0 "F.Cu" signal "TOP")
		(4 "In1.Cu" signal "L02_GND1")
		(6 "In2.Cu" signal "L03_SIG1")
		(8 "In3.Cu" signal "L04_GND2")
		(10 "In4.Cu" signal "L05_VCC1")
		(12 "In5.Cu" signal "L06_VCC2")
		(14 "In6.Cu" signal "L07_GND3")
		(16 "In7.Cu" signal "L08_SIG2")
		(18 "In8.Cu" signal "L09_GND4")
		(2 "B.Cu" signal "BOTTOM")
		(9 "F.Adhes" user "F.Adhesive")
		(11 "B.Adhes" user "B.Adhesive")
		(13 "F.Paste" user "Package Geometry/Pastemask Top")
		(15 "B.Paste" user "Package Geometry/Pastemask Bottom")
		(5 "F.SilkS" user "Ref Des/Silkscreen Top")
		(7 "B.SilkS" user "Ref Des/Silkscreen Bottom")
		(1 "F.Mask" user "Board Geometry/Soldermask Top")
		(3 "B.Mask" user "Board Geometry/Soldermask Bottom")
		(17 "Dwgs.User" user "User.Drawings")
		(19 "Cmts.User" user "User.Comments")
		(21 "Eco1.User" user "User.Eco1")
		(23 "Eco2.User" user "User.Eco2")
		(25 "Edge.Cuts" user "Board Geometry/Outline")
		(27 "Margin" user)
		(31 "F.CrtYd" user "Package Geometry/Place Bound Top")
		(29 "B.CrtYd" user "Package Geometry/Place Bound Bottom")
		(35 "F.Fab" user "Ref Des/Assembly Top")
		(33 "B.Fab" user "Ref Des/Assembly Bottom")
	)
	(footprint ""
		(layer "F.Cu")
		(at 38.862 -76.835 -90)
		(property "Reference" "R490"
			(at 0.889 3.77063 90)
			(unlocked yes)
			(layer "F.SilkS")
			(effects
				(font
					(size 0.7874 0.5842)
					(thickness 0.1524)
				)
			)
		)
		(property "Value" "VAL*"
			(at 0.02032 2.13233 270)
			(unlocked yes)
			(layer "F.Fab")
			(hide yes)
			(effects
				(font
					(size 0.7874 0.5842)
					(thickness 0.1524)
				)
			)
		)
		(property "Tolerance" "TOL*"
			(at 0.044704 3.05435 270)
			(unlocked yes)
			(layer "Cmts.User")
			(hide yes)
			(effects
				(font
					(size 0.7874 0.5842)
					(thickness 0.1524)
				)
			)
		)
		(property "User Part Number" "PARTNUM*"
			(at 0.02032 4.024884 270)
			(unlocked yes)
			(layer "Cmts.User")
			(hide yes)
			(effects
				(font
					(size 0.7874 0.5842)
					(thickness 0.1524)
				)
			)
		)
		(property "Device Type" "RESISTOR-G155-11002-01,10KOHM,A"
			(at 0.008382 1.210564 270)
			(unlocked yes)
			(layer "F.Fab")
			(hide yes)
			(effects
				(font
					(size 0.7874 0.5842)
					(thickness 0.1524)
				)
			)
		)
		(duplicate_pad_numbers_are_jumpers no)
		(fp_line
			(start -1.143 0.5588)
			(end 1.143 0.5588)
			(stroke
				(width 0.1)
				(type default)
			)
			(layer "F.SilkS")
		)
		(fp_line
			(start 1.143 0.5588)
			(end 1.143 -0.5588)
			(stroke
				(width 0.1)
				(type default)
			)
			(layer "F.SilkS")
		)
		(fp_line
			(start -1.143 -0.5588)
			(end -1.143 0.5588)
			(stroke
				(width 0.1)
				(type default)
			)
			(layer "F.SilkS")
		)
		(fp_line
			(start 1.143 -0.5588)
			(end -1.143 -0.5588)
			(stroke
				(width 0.1)
				(type default)
			)
			(layer "F.SilkS")
		)
		(fp_poly
			(pts
				(xy -1.143 0.5588) (xy 1.143 0.5588) (xy 1.143 -0.5588) (xy -1.143 -0.5588)
			)
			(stroke
				(width 0)
				(type default)
			)
			(fill no)
			(layer "F.CrtYd")
		)
		(fp_line
			(start -0.508 0.3048)
			(end 0.508 0.3048)
			(stroke
				(width 0.1)
				(type default)
			)
			(layer "F.Fab")
		)
		(fp_line
			(start 0.508 0.3048)
			(end 0.508 -0.3048)
			(stroke
				(width 0.1)
				(type default)
			)
			(layer "F.Fab")
		)
		(fp_line
			(start -0.508 -0.3048)
			(end -0.508 0.3048)
			(stroke
				(width 0.1)
				(type default)
			)
			(layer "F.Fab")
		)
		(fp_line
			(start 0.508 -0.3048)
			(end -0.508 -0.3048)
			(stroke
				(width 0.1)
				(type default)
			)
			(layer "F.Fab")
		)
		(pad "1" smd rect
			(at -0.5334 0 270)
			(size 0.7112 0.6096)
			(layers "F.Cu" "F.Mask" "F.Paste")
			(net "XP3R3V_FT4232")
		)
		(pad "2" smd rect
			(at 0.5334 0 270)
			(size 0.7112 0.6096)
			(layers "F.Cu" "F.Mask" "F.Paste")
			(net "UNNAMED_525_ISL80101IRAJZDFN10_")
		)
		(zone
			(layer "F.Cu")
			(hatch none 0.5)
			(connect_pads
				(clearance 0)
			)
			(min_thickness 0.25)
			(keepout
				(tracks allowed)
				(vias not_allowed)
				(pads allowed)
				(copperpour not_allowed)
				(footprints allowed)
			)
			(placement
				(enabled no)
				(sheetname "")
			)
			(fill
				(thermal_gap 0.5)
				(thermal_bridge_width 0.5)
				(island_removal_mode 0)
			)
			(polygon
				(pts
					(xy 38.5572 -76.9112) (xy 38.5572 -76.7588) (xy 39.1668 -76.7588) (xy 39.1668 -76.9112)
				)
			)
		)
		(zone
			(layer "F.Cu")
			(hatch none 0.5)
			(connect_pads
				(clearance 0)
			)
			(min_thickness 0.25)
			(keepout
				(tracks not_allowed)
				(vias allowed)
				(pads allowed)
				(copperpour not_allowed)
				(footprints allowed)
			)
			(placement
				(enabled no)
				(sheetname "")
			)
			(fill
				(thermal_gap 0.5)
				(thermal_bridge_width 0.5)
				(island_removal_mode 0)
			)
			(polygon
				(pts
					(xy 38.5572 -76.9112) (xy 38.5572 -76.7588) (xy 39.1668 -76.7588) (xy 39.1668 -76.9112)
				)
			)
		)
	)
	(footprint ""
		(layer "F.Cu")
		(at 152.883108 -49.01311 -90)
		(property "Reference" "R299"
			(at 0.11811 -2.858262 90)
			(unlocked yes)
			(layer "F.SilkS")
			(effects
				(font
					(size 0.7874 0.5842)
					(thickness 0.1524)
				)
			)
		)
		(property "Value" "VAL*"
			(at 0.02032 2.13233 270)
			(unlocked yes)
			(layer "F.Fab")
			(hide yes)
			(effects
				(font
					(size 0.7874 0.5842)
					(thickness 0.1524)
				)
			)
		)
		(property "Device Type" "RESISTOR-G155-133R0-01,33OHM,1%"
			(at 0.008382 1.210564 270)
			(unlocked yes)
			(layer "F.Fab")
			(hide yes)
			(effects
				(font
					(size 0.7874 0.5842)
					(thickness 0.1524)
				)
			)
		)
		(property "User Part Number" "PARTNUM*"
			(at 0.02032 4.024884 270)
			(unlocked yes)
			(layer "Cmts.User")
			(hide yes)
			(effects
				(font
					(size 0.7874 0.5842)
					(thickness 0.1524)
				)
			)
		)
		(property "Tolerance" "TOL*"
			(at 0.044704 3.05435 270)
			(unlocked yes)
			(layer "Cmts.User")
			(hide yes)
			(effects
				(font
					(size 0.7874 0.5842)
					(thickness 0.1524)
				)
			)
		)
		(duplicate_pad_numbers_are_jumpers no)
		(fp_line
			(start -1.143 0.5588)
			(end 1.143 0.5588)
			(stroke
				(width 0.1)
				(type default)
			)
			(layer "F.SilkS")
		)
		(fp_line
			(start 1.143 0.5588)
			(end 1.143 -0.5588)
			(stroke
				(width 0.1)
				(type default)
			)
			(layer "F.SilkS")
		)
		(fp_line
			(start -1.143 -0.5588)
			(end -1.143 0.5588)
			(stroke
				(width 0.1)
				(type default)
			)
			(layer "F.SilkS")
		)
		(fp_line
			(start 1.143 -0.5588)
			(end -1.143 -0.5588)
			(stroke
				(width 0.1)
				(type default)
			)
			(layer "F.SilkS")
		)
		(fp_rect
			(start -1.143 -0.5588)
			(end 1.143 0.5588)
			(stroke
				(width 0)
				(type default)
			)
			(fill no)
			(layer "F.CrtYd")
		)
		(fp_line
			(start -0.508 0.3048)
			(end 0.508 0.3048)
			(stroke
				(width 0.1)
				(type default)
			)
			(layer "F.Fab")
		)
		(fp_line
			(start 0.508 0.3048)
			(end 0.508 -0.3048)
			(stroke
				(width 0.1)
				(type default)
			)
			(layer "F.Fab")
		)
		(fp_line
			(start -0.508 -0.3048)
			(end -0.508 0.3048)
			(stroke
				(width 0.1)
				(type default)
			)
			(layer "F.Fab")
		)
		(fp_line
			(start 0.508 -0.3048)
			(end -0.508 -0.3048)
			(stroke
				(width 0.1)
				(type default)
			)
			(layer "F.Fab")
		)
		(pad "1" smd rect
			(at -0.5334 0 270)
			(size 0.7112 0.6096)
			(layers "F.Cu" "F.Mask" "F.Paste")
			(net "R_SHT3X_ALERT_N")
		)
		(pad "2" smd rect
			(at 0.5334 0 270)
			(size 0.7112 0.6096)
			(layers "F.Cu" "F.Mask" "F.Paste")
			(net "FPGA_IN_SHT3X_ALERT_N")
		)
		(zone
			(layer "F.Cu")
			(hatch none 0.5)
			(connect_pads
				(clearance 0)
			)
			(min_thickness 0.25)
			(keepout
				(tracks allowed)
				(vias not_allowed)
				(pads allowed)
				(copperpour not_allowed)
				(footprints allowed)
			)
			(placement
				(enabled no)
				(sheetname "")
			)
			(fill
				(thermal_gap 0.5)
				(thermal_bridge_width 0.5)
				(island_removal_mode 0)
			)
			(polygon
				(pts
					(xy 153.187908 -49.08931) (xy 152.578308 -49.08931) (xy 152.578308 -48.93691) (xy 153.187908 -48.93691)
				)
			)
		)
	)
)
